(kicad_pcb
	(version 20241229)
	(generator "pcbnew")
	(generator_version "9.0")
	(general
		(thickness 1.59)
		(legacy_teardrops no)
	)
	(paper "A3")
	(title_block
		(title "usb-c-power-adapter")
		(date "2025-06-24")
		(rev "1.1.2")
		(company "Antmicro")
		(comment 9 "footprints 49-54 of 122")
	)
	(layers
		(0 "F.Cu" signal)
		(4 "In1.Cu" signal)
		(6 "In2.Cu" signal)
		(2 "B.Cu" signal)
		(9 "F.Adhes" user "F.Adhesive")
		(11 "B.Adhes" user "B.Adhesive")
		(13 "F.Paste" user)
		(15 "B.Paste" user)
		(5 "F.SilkS" user "F.Silkscreen")
		(7 "B.SilkS" user "B.Silkscreen")
		(1 "F.Mask" user)
		(3 "B.Mask" user)
		(17 "Dwgs.User" user "User.Drawings")
		(19 "Cmts.User" user "User.Comments")
		(21 "Eco1.User" user "User.Eco1")
		(23 "Eco2.User" user "User.Eco2")
		(25 "Edge.Cuts" user)
		(27 "Margin" user)
		(31 "F.CrtYd" user "F.Courtyard")
		(29 "B.CrtYd" user "B.Courtyard")
		(35 "F.Fab" user)
		(33 "B.Fab" user)
	)
	(footprint "antmicro-footprints:LED_0603_1608Metric_G"
		(layer "F.Cu")
		(at 102.4 74.55 90)
		(descr "LED SMD 0603 Green")
		(tags "LED SMD 0603 Green")
		(property "Reference" "D9"
			(at -3.7 -3.924 0)
			(layer "B.SilkS")
			(effects
				(font
					(size 0.7 0.7)
					(thickness 0.15)
				)
				(justify right bottom mirror)
			)
		)
		(property "Value" "LED_G_0603_LG_L29K-G2J1-24-Z"
			(at -0.001 1.599 90)
			(layer "F.Fab")
			(effects
				(font
					(size 0.7 0.7)
					(thickness 0.15)
				)
				(justify left bottom)
			)
		)
		(property "Datasheet" "https://look.ams-osram.com/m/19ee86b3ae0ee95b/original/LG-L29K.pdf"
			(at 0 0 90)
			(layer "F.Fab")
			(hide yes)
			(effects
				(font
					(size 1.27 1.27)
					(thickness 0.15)
				)
			)
		)
		(property "Description" "LED, Green, SMD, 0603, 20 mA, 1.7 V, 570 nm"
			(at 0 0 90)
			(layer "F.Fab")
			(hide yes)
			(effects
				(font
					(size 1.27 1.27)
					(thickness 0.15)
				)
			)
		)
		(property "MPN" "LG L29K-G2J1-24-Z"
			(at 0 0 90)
			(unlocked yes)
			(layer "F.Fab")
			(hide yes)
			(effects
				(font
					(size 1 1)
					(thickness 0.15)
				)
			)
		)
		(property "Manufacturer" "OSRAM"
			(at 0 0 90)
			(unlocked yes)
			(layer "F.Fab")
			(hide yes)
			(effects
				(font
					(size 1 1)
					(thickness 0.15)
				)
			)
		)
		(property "Color" "Green"
			(at 0 0 90)
			(unlocked yes)
			(layer "F.Fab")
			(hide yes)
			(effects
				(font
					(size 1 1)
					(thickness 0.15)
				)
			)
		)
		(property "Author" "Antmicro"
			(at 0 0 90)
			(unlocked yes)
			(layer "F.Fab")
			(hide yes)
			(effects
				(font
					(size 1 1)
					(thickness 0.15)
				)
			)
		)
		(property "License" "Apache-2.0"
			(at 0 0 90)
			(unlocked yes)
			(layer "F.Fab")
			(hide yes)
			(effects
				(font
					(size 1 1)
					(thickness 0.15)
				)
			)
		)
		(sheetname "/DC-DC Converters/")
		(sheetfile "dc-dc_converters.kicad_sch")
		(attr smd)
		(fp_line
			(start 0.22 -0.35)
			(end -0.22 -0.35)
			(stroke
				(width 0.15)
				(type solid)
			)
			(layer "F.SilkS")
		)
		(fp_line
			(start -1.18 -0.319)
			(end -1.18 0.321)
			(stroke
				(width 0.15)
				(type solid)
			)
			(layer "F.SilkS")
		)
		(fp_line
			(start 0.105328 0.001008)
			(end 0.24 0.001)
			(stroke
				(width 0.1)
				(type solid)
			)
			(layer "F.SilkS")
		)
		(fp_line
			(start -0.094672 0.001008)
			(end 0.105328 -0.198992)
			(stroke
				(width 0.1)
				(type solid)
			)
			(layer "F.SilkS")
		)
		(fp_line
			(start -0.094672 0.001008)
			(end -0.24 0.001008)
			(stroke
				(width 0.1)
				(type solid)
			)
			(layer "F.SilkS")
		)
		(fp_line
			(start 0.105328 0.201008)
			(end 0.105328 -0.198992)
			(stroke
				(width 0.1)
				(type solid)
			)
			(layer "F.SilkS")
		)
		(fp_line
			(start 0.105328 0.201008)
			(end -0.094672 0.001008)
			(stroke
				(width 0.1)
				(type solid)
			)
			(layer "F.SilkS")
		)
		(fp_line
			(start -0.094672 0.201008)
			(end -0.094672 -0.198992)
			(stroke
				(width 0.1)
				(type solid)
			)
			(layer "F.SilkS")
		)
		(fp_line
			(start 0.22 0.35)
			(end -0.22 0.35)
			(stroke
				(width 0.15)
				(type solid)
			)
			(layer "F.SilkS")
		)
		(fp_rect
			(start 1.25 0.65)
			(end -1.25 -0.65)
			(stroke
				(width 0.05)
				(type solid)
			)
			(fill no)
			(layer "F.CrtYd")
		)
		(fp_line
			(start 0.201 -0.202)
			(end -0.101 0)
			(stroke
				(width 0.15)
				(type solid)
			)
			(layer "F.Fab")
		)
		(fp_line
			(start -0.199 -0.202)
			(end -0.199 0.1)
			(stroke
				(width 0.15)
				(type solid)
			)
			(layer "F.Fab")
		)
		(fp_line
			(start 0.599 0)
			(end 0.201 0)
			(stroke
				(width 0.15)
				(type solid)
			)
			(layer "F.Fab")
		)
		(fp_line
			(start 0.201 0)
			(end 0.201 -0.202)
			(stroke
				(width 0.15)
				(type solid)
			)
			(layer "F.Fab")
		)
		(fp_line
			(start -0.101 0)
			(end 0.201 0.2)
			(stroke
				(width 0.15)
				(type solid)
			)
			(layer "F.Fab")
		)
		(fp_line
			(start -0.199 0)
			(end -0.597 0)
			(stroke
				(width 0.15)
				(type solid)
			)
			(layer "F.Fab")
		)
		(fp_line
			(start 0.201 0.2)
			(end 0.201 0)
			(stroke
				(width 0.15)
				(type solid)
			)
			(layer "F.Fab")
		)
		(fp_line
			(start -0.199 0.2)
			(end -0.199 0.1)
			(stroke
				(width 0.15)
				(type solid)
			)
			(layer "F.Fab")
		)
		(fp_rect
			(start 0.848 0.4)
			(end -0.85 -0.402)
			(stroke
				(width 0.15)
				(type solid)
			)
			(fill no)
			(layer "F.Fab")
		)
		(pad "1" smd roundrect
			(at -0.7 0 270)
			(size 0.8 1)
			(layers "F.Cu" "F.Mask" "F.Paste")
			(roundrect_rratio 0.2)
			(net 2 "GND")
			(pinfunction "C")
			(pintype "passive")
		)
		(pad "2" smd roundrect
			(at 0.7 0 270)
			(size 0.8 1)
			(layers "F.Cu" "F.Mask" "F.Paste")
			(roundrect_rratio 0.2)
			(net 69 "Net-(D9-A)")
			(pinfunction "A")
			(pintype "passive")
		)
	)
	(footprint "antmicro-footprints:LED_0603_1608Metric_G"
		(layer "F.Cu")
		(at 99.7 74.55 90)
		(descr "LED SMD 0603 Green")
		(tags "LED SMD 0603 Green")
		(property "Reference" "D7"
			(at -5.8 -1.224 0)
			(layer "B.SilkS")
			(effects
				(font
					(size 0.7 0.7)
					(thickness 0.15)
				)
				(justify right bottom mirror)
			)
		)
		(property "Value" "LED_G_0603_LG_L29K-G2J1-24-Z"
			(at -0.001 1.599 90)
			(layer "F.Fab")
			(effects
				(font
					(size 0.7 0.7)
					(thickness 0.15)
				)
				(justify left bottom)
			)
		)
		(property "Datasheet" "https://look.ams-osram.com/m/19ee86b3ae0ee95b/original/LG-L29K.pdf"
			(at 0 0 90)
			(layer "F.Fab")
			(hide yes)
			(effects
				(font
					(size 1.27 1.27)
					(thickness 0.15)
				)
			)
		)
		(property "Description" "LED, Green, SMD, 0603, 20 mA, 1.7 V, 570 nm"
			(at 0 0 90)
			(layer "F.Fab")
			(hide yes)
			(effects
				(font
					(size 1.27 1.27)
					(thickness 0.15)
				)
			)
		)
		(property "MPN" "LG L29K-G2J1-24-Z"
			(at 0 0 90)
			(unlocked yes)
			(layer "F.Fab")
			(hide yes)
			(effects
				(font
					(size 1 1)
					(thickness 0.15)
				)
			)
		)
		(property "Manufacturer" "OSRAM"
			(at 0 0 90)
			(unlocked yes)
			(layer "F.Fab")
			(hide yes)
			(effects
				(font
					(size 1 1)
					(thickness 0.15)
				)
			)
		)
		(property "Color" "Green"
			(at 0 0 90)
			(unlocked yes)
			(layer "F.Fab")
			(hide yes)
			(effects
				(font
					(size 1 1)
					(thickness 0.15)
				)
			)
		)
		(property "Author" "Antmicro"
			(at 0 0 90)
			(unlocked yes)
			(layer "F.Fab")
			(hide yes)
			(effects
				(font
					(size 1 1)
					(thickness 0.15)
				)
			)
		)
		(property "License" "Apache-2.0"
			(at 0 0 90)
			(unlocked yes)
			(layer "F.Fab")
			(hide yes)
			(effects
				(font
					(size 1 1)
					(thickness 0.15)
				)
			)
		)
		(sheetname "/USB PD/")
		(sheetfile "usb_pd.kicad_sch")
		(attr smd)
		(fp_line
			(start 0.22 -0.35)
			(end -0.22 -0.35)
			(stroke
				(width 0.15)
				(type solid)
			)
			(layer "F.SilkS")
		)
		(fp_line
			(start -1.18 -0.319)
			(end -1.18 0.321)
			(stroke
				(width 0.15)
				(type solid)
			)
			(layer "F.SilkS")
		)
		(fp_line
			(start 0.105328 0.001008)
			(end 0.24 0.001)
			(stroke
				(width 0.1)
				(type solid)
			)
			(layer "F.SilkS")
		)
		(fp_line
			(start -0.094672 0.001008)
			(end 0.105328 -0.198992)
			(stroke
				(width 0.1)
				(type solid)
			)
			(layer "F.SilkS")
		)
		(fp_line
			(start -0.094672 0.001008)
			(end -0.24 0.001008)
			(stroke
				(width 0.1)
				(type solid)
			)
			(layer "F.SilkS")
		)
		(fp_line
			(start 0.105328 0.201008)
			(end 0.105328 -0.198992)
			(stroke
				(width 0.1)
				(type solid)
			)
			(layer "F.SilkS")
		)
		(fp_line
			(start 0.105328 0.201008)
			(end -0.094672 0.001008)
			(stroke
				(width 0.1)
				(type solid)
			)
			(layer "F.SilkS")
		)
		(fp_line
			(start -0.094672 0.201008)
			(end -0.094672 -0.198992)
			(stroke
				(width 0.1)
				(type solid)
			)
			(layer "F.SilkS")
		)
		(fp_line
			(start 0.22 0.35)
			(end -0.22 0.35)
			(stroke
				(width 0.15)
				(type solid)
			)
			(layer "F.SilkS")
		)
		(fp_rect
			(start 1.25 0.65)
			(end -1.25 -0.65)
			(stroke
				(width 0.05)
				(type solid)
			)
			(fill no)
			(layer "F.CrtYd")
		)
		(fp_line
			(start 0.201 -0.202)
			(end -0.101 0)
			(stroke
				(width 0.15)
				(type solid)
			)
			(layer "F.Fab")
		)
		(fp_line
			(start -0.199 -0.202)
			(end -0.199 0.1)
			(stroke
				(width 0.15)
				(type solid)
			)
			(layer "F.Fab")
		)
		(fp_line
			(start 0.599 0)
			(end 0.201 0)
			(stroke
				(width 0.15)
				(type solid)
			)
			(layer "F.Fab")
		)
		(fp_line
			(start 0.201 0)
			(end 0.201 -0.202)
			(stroke
				(width 0.15)
				(type solid)
			)
			(layer "F.Fab")
		)
		(fp_line
			(start -0.101 0)
			(end 0.201 0.2)
			(stroke
				(width 0.15)
				(type solid)
			)
			(layer "F.Fab")
		)
		(fp_line
			(start -0.199 0)
			(end -0.597 0)
			(stroke
				(width 0.15)
				(type solid)
			)
			(layer "F.Fab")
		)
		(fp_line
			(start 0.201 0.2)
			(end 0.201 0)
			(stroke
				(width 0.15)
				(type solid)
			)
			(layer "F.Fab")
		)
		(fp_line
			(start -0.199 0.2)
			(end -0.199 0.1)
			(stroke
				(width 0.15)
				(type solid)
			)
			(layer "F.Fab")
		)
		(fp_rect
			(start 0.848 0.4)
			(end -0.85 -0.402)
			(stroke
				(width 0.15)
				(type solid)
			)
			(fill no)
			(layer "F.Fab")
		)
		(pad "1" smd roundrect
			(at -0.7 0 270)
			(size 0.8 1)
			(layers "F.Cu" "F.Mask" "F.Paste")
			(roundrect_rratio 0.2)
			(net 28 "POWER_OK3")
			(pinfunction "C")
			(pintype "passive")
		)
		(pad "2" smd roundrect
			(at 0.7 0 270)
			(size 0.8 1)
			(layers "F.Cu" "F.Mask" "F.Paste")
			(roundrect_rratio 0.2)
			(net 67 "Net-(D7-A)")
			(pinfunction "A")
			(pintype "passive")
		)
	)
	(footprint "antmicro-footprints:R_0402_1005Metric"
		(layer "F.Cu")
		(at 100 84.577)
		(descr "Resistor SMD 0402")
		(tags "resistor SMD 0402")
		(property "Reference" "R17"
			(at 1.092 0.513 0)
			(layer "F.SilkS")
			(effects
				(font
					(size 0.7 0.7)
					(thickness 0.15)
				)
				(justify left bottom)
			)
		)
		(property "Value" "R_140k_0.1%_0402"
			(at -1.011843 1.772047 0)
			(layer "F.Fab")
			(effects
				(font
					(size 0.7 0.7)
					(thickness 0.15)
				)
				(justify left bottom)
			)
		)
		(property "Datasheet" "https://www.vishay.com/docs/28758/tnpw_e3.pdf"
			(at 0 0 0)
			(layer "F.Fab")
			(hide yes)
			(effects
				(font
					(size 1.27 1.27)
					(thickness 0.15)
				)
			)
		)
		(property "Description" "SMD Chip Resistor, Ceramic, 140 kohm, ± 0.1%, 62.5 mW, 0402 [1005 Metric], Thin Film, Precision resistors"
			(at 0 0 0)
			(layer "F.Fab")
			(hide yes)
			(effects
				(font
					(size 1.27 1.27)
					(thickness 0.15)
				)
			)
		)
		(property "MPN" "RT0402BRD07140KL"
			(at 0 0 0)
			(unlocked yes)
			(layer "F.Fab")
			(hide yes)
			(effects
				(font
					(size 1 1)
					(thickness 0.15)
				)
			)
		)
		(property "Val" "140k"
			(at 0 0 0)
			(unlocked yes)
			(layer "F.Fab")
			(hide yes)
			(effects
				(font
					(size 1 1)
					(thickness 0.15)
				)
			)
		)
		(property "Manufacturer" "YAGEO"
			(at 0 0 0)
			(unlocked yes)
			(layer "F.Fab")
			(hide yes)
			(effects
				(font
					(size 1 1)
					(thickness 0.15)
				)
			)
		)
		(property "Tolerance" "0.1%"
			(at 0 0 0)
			(unlocked yes)
			(layer "F.Fab")
			(hide yes)
			(effects
				(font
					(size 1 1)
					(thickness 0.15)
				)
			)
		)
		(property "License" "Apache-2.0"
			(at 0 0 0)
			(unlocked yes)
			(layer "F.Fab")
			(hide yes)
			(effects
				(font
					(size 1 1)
					(thickness 0.15)
				)
			)
		)
		(property "Author" "Antmicro"
			(at 0 0 0)
			(unlocked yes)
			(layer "F.Fab")
			(hide yes)
			(effects
				(font
					(size 1 1)
					(thickness 0.15)
				)
			)
		)
		(sheetname "/DC-DC Converters/")
		(sheetfile "dc-dc_converters.kicad_sch")
		(attr smd)
		(fp_rect
			(start -0.925 -0.47)
			(end 0.925 0.47)
			(stroke
				(width 0.05)
				(type default)
			)
			(fill no)
			(layer "F.CrtYd")
		)
		(fp_rect
			(start -0.5 -0.25)
			(end 0.5 0.25)
			(stroke
				(width 0.15)
				(type solid)
			)
			(fill no)
			(layer "F.Fab")
		)
		(pad "1" smd roundrect
			(at -0.48 0)
			(size 0.59 0.64)
			(layers "F.Cu" "F.Mask" "F.Paste")
			(roundrect_rratio 0.25)
			(net 51 "Net-(U2-V_{FB})")
			(pintype "passive")
		)
		(pad "2" smd roundrect
			(at 0.48 0)
			(size 0.59 0.64)
			(layers "F.Cu" "F.Mask" "F.Paste")
			(roundrect_rratio 0.25)
			(net 5 "+12V")
			(pintype "passive")
		)
	)
	(footprint "antmicro-footprints:R_0402_1005Metric"
		(layer "F.Cu")
		(at 83.35 69.75 90)
		(descr "Resistor SMD 0402")
		(tags "resistor SMD 0402")
		(property "Reference" "R31"
			(at 1.17 0.47 90)
			(layer "F.SilkS")
			(effects
				(font
					(size 0.7 0.7)
					(thickness 0.15)
				)
				(justify left bottom)
			)
		)
		(property "Value" "R_4k7_0402"
			(at -1.011843 1.772047 90)
			(layer "F.Fab")
			(effects
				(font
					(size 0.7 0.7)
					(thickness 0.15)
				)
				(justify left bottom)
			)
		)
		(property "Datasheet" "https://www.bourns.com/docs/product-datasheets/cr.pdf"
			(at 0 0 90)
			(layer "F.Fab")
			(hide yes)
			(effects
				(font
					(size 1.27 1.27)
					(thickness 0.15)
				)
			)
		)
		(property "Description" "SMD Chip Resistor, 4.7 kohm, ± 1%, 62.5 mW, 0402 [1005 Metric], Thick Film, General Purpose"
			(at 0 0 90)
			(layer "F.Fab")
			(hide yes)
			(effects
				(font
					(size 1.27 1.27)
					(thickness 0.15)
				)
			)
		)
		(property "MPN" "CR0402-FX-4701GLF"
			(at 0 0 90)
			(unlocked yes)
			(layer "F.Fab")
			(hide yes)
			(effects
				(font
					(size 1 1)
					(thickness 0.15)
				)
			)
		)
		(property "Manufacturer" "Bourns"
			(at 0 0 90)
			(unlocked yes)
			(layer "F.Fab")
			(hide yes)
			(effects
				(font
					(size 1 1)
					(thickness 0.15)
				)
			)
		)
		(property "License" "Apache-2.0"
			(at 0 0 90)
			(unlocked yes)
			(layer "F.Fab")
			(hide yes)
			(effects
				(font
					(size 1 1)
					(thickness 0.15)
				)
			)
		)
		(property "Author" "Antmicro"
			(at 0 0 90)
			(unlocked yes)
			(layer "F.Fab")
			(hide yes)
			(effects
				(font
					(size 1 1)
					(thickness 0.15)
				)
			)
		)
		(property "Val" "4k7"
			(at 0 0 90)
			(unlocked yes)
			(layer "F.Fab")
			(hide yes)
			(effects
				(font
					(size 1 1)
					(thickness 0.15)
				)
			)
		)
		(property "Tolerance" "1%"
			(at 0 0 90)
			(unlocked yes)
			(layer "F.Fab")
			(hide yes)
			(effects
				(font
					(size 1 1)
					(thickness 0.15)
				)
			)
		)
		(sheetname "/USB PD/")
		(sheetfile "usb_pd.kicad_sch")
		(attr smd exclude_from_pos_files exclude_from_bom dnp)
		(fp_rect
			(start -0.925 -0.47)
			(end 0.925 0.47)
			(stroke
				(width 0.05)
				(type default)
			)
			(fill no)
			(layer "F.CrtYd")
		)
		(fp_rect
			(start -0.5 -0.25)
			(end 0.5 0.25)
			(stroke
				(width 0.15)
				(type solid)
			)
			(fill no)
			(layer "F.Fab")
		)
		(pad "1" smd roundrect
			(at -0.48 0 90)
			(size 0.59 0.64)
			(layers "F.Cu" "F.Mask" "F.Paste")
			(roundrect_rratio 0.25)
			(net 38 "/USB PD/SCL")
			(pintype "passive")
		)
		(pad "2" smd roundrect
			(at 0.48 0 90)
			(size 0.59 0.64)
			(layers "F.Cu" "F.Mask" "F.Paste")
			(roundrect_rratio 0.25)
			(net 1 "+3V3")
			(pintype "passive")
		)
	)
	(footprint "antmicro-footprints:TP_SMD_0.75mm"
		(layer "F.Cu")
		(at 88.601 75.125)
		(property "Reference" "TP9"
			(at 5.684 -5.15 0)
			(layer "F.SilkS")
			(hide yes)
			(effects
				(font
					(size 0.7 0.7)
					(thickness 0.15)
				)
				(justify left bottom)
			)
		)
		(property "Value" "TP_0.75mm_SMD"
			(at 0 1.2 0)
			(layer "F.Fab")
			(effects
				(font
					(size 0.7 0.7)
					(thickness 0.15)
				)
				(justify left bottom)
			)
		)
		(property "Description" "SMT test point"
			(at 0 0 0)
			(layer "F.Fab")
			(hide yes)
			(effects
				(font
					(size 1.27 1.27)
					(thickness 0.15)
				)
			)
		)
		(property "MPN" ""
			(at 0 0 0)
			(unlocked yes)
			(layer "F.Fab")
			(hide yes)
			(effects
				(font
					(size 1 1)
					(thickness 0.15)
				)
			)
		)
		(property "Manufacturer" ""
			(at 0 0 0)
			(unlocked yes)
			(layer "F.Fab")
			(hide yes)
			(effects
				(font
					(size 1 1)
					(thickness 0.15)
				)
			)
		)
		(property "Author" "Antmicro"
			(at 0 0 0)
			(unlocked yes)
			(layer "F.Fab")
			(hide yes)
			(effects
				(font
					(size 1 1)
					(thickness 0.15)
				)
			)
		)
		(property "License" "Apache-2.0"
			(at 0 0 0)
			(unlocked yes)
			(layer "F.Fab")
			(hide yes)
			(effects
				(font
					(size 1 1)
					(thickness 0.15)
				)
			)
		)
		(sheetname "/USB PD/")
		(sheetfile "usb_pd.kicad_sch")
		(attr exclude_from_bom)
		(fp_circle
			(center 0 0)
			(end 0.475 0)
			(stroke
				(width 0.05)
				(type default)
			)
			(fill no)
			(layer "F.CrtYd")
		)
		(pad "1" smd circle
			(at 0 0)
			(size 0.75 0.75)
			(layers "F.Cu" "F.Mask")
			(net 54 "Net-(U1-~{ALERT})")
			(pinfunction "1")
			(pintype "passive")
		)
	)
	(footprint "antmicro-footprints:TP_SMD_0.75mm"
		(layer "F.Cu")
		(at 82.696 75.36 180)
		(property "Reference" "TP8"
			(at 1.9812 -1.5748 90)
			(layer "F.SilkS")
			(hide yes)
			(effects
				(font
					(size 0.7 0.7)
					(thickness 0.15)
				)
				(justify left bottom)
			)
		)
		(property "Value" "TP_0.75mm_SMD"
			(at 0 1.2 0)
			(layer "F.Fab")
			(effects
				(font
					(size 0.7 0.7)
					(thickness 0.15)
				)
				(justify right bottom)
			)
		)
		(property "Description" "SMT test point"
			(at 0 0 180)
			(layer "F.Fab")
			(hide yes)
			(effects
				(font
					(size 1.27 1.27)
					(thickness 0.15)
				)
			)
		)
		(property "MPN" ""
			(at 0 0 180)
			(unlocked yes)
			(layer "F.Fab")
			(hide yes)
			(effects
				(font
					(size 1 1)
					(thickness 0.15)
				)
			)
		)
		(property "Manufacturer" ""
			(at 0 0 180)
			(unlocked yes)
			(layer "F.Fab")
			(hide yes)
			(effects
				(font
					(size 1 1)
					(thickness 0.15)
				)
			)
		)
		(property "Author" "Antmicro"
			(at 0 0 180)
			(unlocked yes)
			(layer "F.Fab")
			(hide yes)
			(effects
				(font
					(size 1 1)
					(thickness 0.15)
				)
			)
		)
		(property "License" "Apache-2.0"
			(at 0 0 180)
			(unlocked yes)
			(layer "F.Fab")
			(hide yes)
			(effects
				(font
					(size 1 1)
					(thickness 0.15)
				)
			)
		)
		(sheetname "/USB PD/")
		(sheetfile "usb_pd.kicad_sch")
		(attr exclude_from_bom)
		(fp_circle
			(center 0 0)
			(end 0.475 0)
			(stroke
				(width 0.05)
				(type default)
			)
			(fill no)
			(layer "F.CrtYd")
		)
		(pad "1" smd circle
			(at 0 0 180)
			(size 0.75 0.75)
			(layers "F.Cu" "F.Mask")
			(net 42 "Net-(U1-RESET)")
			(pinfunction "1")
			(pintype "passive")
		)
	)
)
